# BASEBOARD_FAB2 (Tioga Pass) — schematic netlist excerpt (pin names and nets, part order shuffled) for the footprints in the layout excerpt that follows; sources: Cadence DE-HDL packaged netlist, KiCad conversion of Wiwynn_Tioga_Pass_MB.brd

U1R2  TTL1G126_A  74HC1G126 IC  pkg SOT  page 170
  OE  = FM_FAST_PROCHOT_EN
  A  = FM_FAST_PROCHOT_THROTTLE_DLY_N
  Y  = FM_FAST_PROCHOT_THROTTLE_DLY_BU

C2M25  CAP_A  1.0UF 6.3V 10% X6S  pkg 0402V  page 127 : A = P1V05_PCH_STBY ; B = GND
R8D36  RES  33.2 1% CHIP  pkg 0402  page 157 : A = RST_BMC_SRST_R2_N ; B = RST_BMC_DDR3_BUF_IN_N

(kicad_pcb
	(version 20260206)
	(generator "pcbnew")
	(generator_version "10.0")
	(general
		(thickness 1.6)
		(legacy_teardrops no)
	)
	(paper "A4")
	(title_block
		(title "Wiwynn_Tioga_Pass_MB.brd")
		(comment 1 "Tioga Pass / footprints 3792-3794 of 4770")
	)
	(layers
		(0 "F.Cu" signal "TOP")
		(4 "In1.Cu" signal "L2GND")
		(6 "In2.Cu" signal "L3")
		(8 "In3.Cu" signal "L4GND")
		(10 "In4.Cu" signal "L5")
		(12 "In5.Cu" signal "L6GND")
		(14 "In6.Cu" signal "L7VCC")
		(16 "In7.Cu" signal "L8VCC")
		(18 "In8.Cu" signal "L9GND")
		(20 "In9.Cu" signal "L10")
		(22 "In10.Cu" signal "L11GND")
		(24 "In11.Cu" signal "L12")
		(26 "In12.Cu" signal "L13GND")
		(2 "B.Cu" signal "BOTTOM")
		(9 "F.Adhes" user "F.Adhesive")
		(11 "B.Adhes" user "B.Adhesive")
		(13 "F.Paste" user "Package Geometry/Pastemask Top")
		(15 "B.Paste" user "Package Geometry/Pastemask Bottom")
		(5 "F.SilkS" user "Ref Des/Silkscreen Top")
		(7 "B.SilkS" user "Ref Des/Silkscreen Bottom")
		(1 "F.Mask" user "Board Geometry/Soldermask Top")
		(3 "B.Mask" user "Board Geometry/Soldermask Bottom")
		(17 "Dwgs.User" user "User.Drawings")
		(19 "Cmts.User" user "User.Comments")
		(21 "Eco1.User" user "User.Eco1")
		(23 "Eco2.User" user "User.Eco2")
		(25 "Edge.Cuts" user "Board Geometry/Outline")
		(27 "Margin" user)
		(31 "F.CrtYd" user "Package Geometry/Place Bound Top")
		(29 "B.CrtYd" user "Package Geometry/Place Bound Bottom")
		(35 "F.Fab" user "Ref Des/Assembly Top")
		(33 "B.Fab" user "Ref Des/Assembly Bottom")
	)
	(footprint ""
		(layer "B.Cu")
		(at 403.01418 -117.6655 180)
		(property "Reference" "C2M25"
			(at 0 0 0)
			(layer "B.SilkS")
			(hide yes)
			(effects
				(font
					(size 1.27 1.27)
				)
				(justify mirror)
			)
		)
		(property "Value" ""
			(at 0 0 0)
			(layer "B.Fab")
			(effects
				(font
					(size 1.27 1.27)
				)
				(justify mirror)
			)
		)
		(duplicate_pad_numbers_are_jumpers no)
		(fp_poly
			(pts
				(xy -0.3048 -0.1016) (xy -0.3048 0.9906) (xy 0.3048 0.9906) (xy 0.3048 -0.1016)
			)
			(stroke
				(width 0)
				(type default)
			)
			(fill no)
			(layer "B.CrtYd")
		)
		(fp_line
			(start 0.3048 0.9906)
			(end -0.3048 0.9906)
			(stroke
				(width 0.1)
				(type default)
			)
			(layer "B.Fab")
		)
		(fp_line
			(start 0.3048 -0.1016)
			(end 0.3048 0.9906)
			(stroke
				(width 0.1)
				(type default)
			)
			(layer "B.Fab")
		)
		(fp_line
			(start -0.3048 0.9906)
			(end -0.3048 -0.1016)
			(stroke
				(width 0.1)
				(type default)
			)
			(layer "B.Fab")
		)
		(fp_line
			(start -0.3048 -0.1016)
			(end 0.3048 -0.1016)
			(stroke
				(width 0.1)
				(type default)
			)
			(layer "B.Fab")
		)
		(pad "1" smd rect
			(at 0 0)
			(size 0.508 0.508)
			(layers "B.Cu" "B.Mask" "B.Paste")
			(net "P1V05_PCH_STBY")
		)
		(pad "2" smd rect
			(at 0 0.889)
			(size 0.508 0.508)
			(layers "B.Cu" "B.Mask" "B.Paste")
			(net "GND")
		)
		(zone
			(layer "B.Cu")
			(hatch none 0.5)
			(connect_pads
				(clearance 0)
			)
			(min_thickness 0.25)
			(keepout
				(tracks not_allowed)
				(vias allowed)
				(pads allowed)
				(copperpour not_allowed)
				(footprints allowed)
			)
			(placement
				(enabled no)
				(sheetname "")
			)
			(fill
				(thermal_gap 0.5)
				(thermal_bridge_width 0.5)
				(island_removal_mode 0)
			)
			(polygon
				(pts
					(xy 402.76018 -118.3005) (xy 403.26818 -118.3005) (xy 403.26818 -117.9195) (xy 402.76018 -117.9195)
				)
			)
		)
		(zone
			(layer "B.Cu")
			(hatch none 0.5)
			(connect_pads
				(clearance 0)
			)
			(min_thickness 0.25)
			(keepout
				(tracks allowed)
				(vias not_allowed)
				(pads allowed)
				(copperpour not_allowed)
				(footprints allowed)
			)
			(placement
				(enabled no)
				(sheetname "")
			)
			(fill
				(thermal_gap 0.5)
				(thermal_bridge_width 0.5)
				(island_removal_mode 0)
			)
			(polygon
				(pts
					(xy 402.76018 -117.9195) (xy 403.26818 -117.9195) (xy 403.26818 -118.3005) (xy 402.76018 -118.3005)
				)
			)
		)
	)
	(footprint ""
		(layer "B.Cu")
		(at 455.200258 -31.237174 -90)
		(property "Reference" "R8D36"
			(at 0 0 90)
			(layer "B.SilkS")
			(hide yes)
			(effects
				(font
					(size 1.27 1.27)
				)
				(justify mirror)
			)
		)
		(property "Value" ""
			(at 0 0 90)
			(layer "B.Fab")
			(effects
				(font
					(size 1.27 1.27)
				)
				(justify mirror)
			)
		)
		(duplicate_pad_numbers_are_jumpers no)
		(fp_poly
			(pts
				(xy 0.2794 -0.1016) (xy -0.2794 -0.1016) (xy -0.2794 0.9906) (xy 0.2794 0.9906)
			)
			(stroke
				(width 0)
				(type default)
			)
			(fill no)
			(layer "B.CrtYd")
		)
		(fp_line
			(start -0.2794 0.9906)
			(end -0.2794 -0.1016)
			(stroke
				(width 0.1)
				(type default)
			)
			(layer "B.Fab")
		)
		(fp_line
			(start 0.2794 0.9906)
			(end -0.2794 0.9906)
			(stroke
				(width 0.1)
				(type default)
			)
			(layer "B.Fab")
		)
		(fp_line
			(start -0.2794 -0.1016)
			(end 0.2794 -0.1016)
			(stroke
				(width 0.1)
				(type default)
			)
			(layer "B.Fab")
		)
		(fp_line
			(start 0.2794 -0.1016)
			(end 0.2794 0.9906)
			(stroke
				(width 0.1)
				(type default)
			)
			(layer "B.Fab")
		)
		(pad "1" smd rect
			(at 0 0 90)
			(size 0.508 0.508)
			(layers "B.Cu" "B.Mask" "B.Paste")
			(net "RST_BMC_SRST_R2_N")
		)
		(pad "2" smd rect
			(at 0 0.889 90)
			(size 0.508 0.508)
			(layers "B.Cu" "B.Mask" "B.Paste")
			(net "RST_BMC_DDR3_BUF_IN_N")
		)
		(zone
			(layer "B.Cu")
			(hatch none 0.5)
			(connect_pads
				(clearance 0)
			)
			(min_thickness 0.25)
			(keepout
				(tracks not_allowed)
				(vias allowed)
				(pads allowed)
				(copperpour not_allowed)
				(footprints allowed)
			)
			(placement
				(enabled no)
				(sheetname "")
			)
			(fill
				(thermal_gap 0.5)
				(thermal_bridge_width 0.5)
				(island_removal_mode 0)
			)
			(polygon
				(pts
					(xy 454.565258 -30.983174) (xy 454.565258 -31.491174) (xy 454.946258 -31.491174) (xy 454.946258 -30.983174)
				)
			)
		)
		(zone
			(layer "B.Cu")
			(hatch none 0.5)
			(connect_pads
				(clearance 0)
			)
			(min_thickness 0.25)
			(keepout
				(tracks allowed)
				(vias not_allowed)
				(pads allowed)
				(copperpour not_allowed)
				(footprints allowed)
			)
			(placement
				(enabled no)
				(sheetname "")
			)
			(fill
				(thermal_gap 0.5)
				(thermal_bridge_width 0.5)
				(island_removal_mode 0)
			)
			(polygon
				(pts
					(xy 454.946258 -30.983174) (xy 454.946258 -31.491174) (xy 454.565258 -31.491174) (xy 454.565258 -30.983174)
				)
			)
		)
	)
	(footprint ""
		(layer "B.Cu")
		(at 416.889184 -75.296014 180)
		(property "Reference" "U1R2"
			(at -0.35433 2.159 270)
			(unlocked yes)
			(layer "B.SilkS")
			(effects
				(font
					(size 0.7874 0.5842)
					(thickness 0.1524)
				)
				(justify left mirror)
			)
		)
		(property "Value" ""
			(at 0 0 0)
			(layer "B.Fab")
			(effects
				(font
					(size 1.27 1.27)
				)
				(justify mirror)
			)
		)
		(duplicate_pad_numbers_are_jumpers no)
		(fp_circle
			(center 0.4699 -0.8382)
			(end 0.3429 -0.8382)
			(stroke
				(width 0.254)
				(type default)
			)
			(fill no)
			(layer "B.SilkS")
		)
		(fp_poly
			(pts
				(xy -0.21463 -0.450088) (xy -1.56337 -0.450088) (xy -1.56337 1.75006) (xy -0.21463 1.75006)
			)
			(stroke
				(width 0)
				(type default)
			)
			(fill no)
			(layer "B.CrtYd")
		)
		(fp_line
			(start -0.21463 1.75006)
			(end -0.21463 -0.450088)
			(stroke
				(width 0.1)
				(type default)
			)
			(layer "B.Fab")
		)
		(fp_line
			(start -0.21463 -0.450088)
			(end -1.56337 -0.450088)
			(stroke
				(width 0.1)
				(type default)
			)
			(layer "B.Fab")
		)
		(fp_line
			(start -1.56337 1.75006)
			(end -0.21463 1.75006)
			(stroke
				(width 0.1)
				(type default)
			)
			(layer "B.Fab")
		)
		(fp_line
			(start -1.56337 -0.450088)
			(end -1.56337 1.75006)
			(stroke
				(width 0.1)
				(type default)
			)
			(layer "B.Fab")
		)
		(fp_circle
			(center 0.4699 -0.8382)
			(end 0.3429 -0.8382)
			(stroke
				(width 0.254)
				(type default)
			)
			(fill no)
			(layer "B.Fab")
		)
		(pad "1" smd rect
			(at 0 0)
			(size 1.016 0.381)
			(layers "B.Cu" "B.Mask" "B.Paste")
			(net "FM_FAST_PROCHOT_EN")
		)
		(pad "2" smd rect
			(at 0 0.649986)
			(size 1.016 0.381)
			(layers "B.Cu" "B.Mask" "B.Paste")
			(net "FM_FAST_PROCHOT_THROTTLE_DLY_N")
		)
		(pad "3" smd rect
			(at 0 1.299972)
			(size 1.016 0.381)
			(layers "B.Cu" "B.Mask" "B.Paste")
			(net "GND")
		)
		(pad "4" smd rect
			(at -1.778 1.299972)
			(size 1.016 0.381)
			(layers "B.Cu" "B.Mask" "B.Paste")
			(net "FM_FAST_PROCHOT_THROTTLE_DLY_BU")
		)
		(pad "5" smd rect
			(at -1.778 0)
			(size 1.016 0.381)
			(layers "B.Cu" "B.Mask" "B.Paste")
			(net "P3V3_STBY")
		)
	)
)
